# S9S_MB_2U (Grand Teton) — schematic netlist excerpt (pin names and nets, part order shuffled) for the footprints in the layout excerpt that follows; sources: Cadence DE-HDL packaged netlist, KiCad conversion of 03242023_DA0F0TMBIJ0_F0T_Motherboard_J_brd_V01_OCP.brd

J15  SCONN288_ADR50017P130CC  SCONN288_ADR50017-P130CC IO  pkg DDR288S_1-1VXB  page 96
  VIN_BULK0  = P12V_S3_AUX_CPU0_NVDIMM
  RFU0  = TP_CHH_CPU0_DIMM1_FRU_0
  VIN_MGMT  = P3V3_AUX
  HSCL  = I3C_SPD_DDREFGH_CPU0_LVC1_SCL_6
  HSDA  = I3C_SPD_DDREFGH_CPU0_LVC1_SDA
  VSS0  = GND
  DQ0_A  = M_H_CPU0_SA_DQ<0>
  VSS1  = GND
  DQ1_A  = M_H_CPU0_SA_DQ<1>
  VSS2  = GND
  DQS0_A_T  = M_H_CPU0_SA_DQS_DP<0>
  DQS0_A_C  = M_H_CPU0_SA_DQS_DN<0>
  VSS3  = GND
  DQ4_A  = M_H_CPU0_SA_DQ<4>
  VSS4  = GND
  DQ5_A  = M_H_CPU0_SA_DQ<5>
  VSS5  = GND
  DQ8_A  = M_H_CPU0_SA_DQ<8>
  VSS6  = GND
  DQ9_A  = M_H_CPU0_SA_DQ<9>
  VSS7  = GND
  DQS1_A_T  = M_H_CPU0_SA_DQS_DP<1>
  DQS1_A_C  = M_H_CPU0_SA_DQS_DN<1>
  VSS8  = GND
  DQ12_A  = M_H_CPU0_SA_DQ<12>
  VSS9  = GND
  DQ13_A  = M_H_CPU0_SA_DQ<13>
  VSS10  = GND
  DQ16_A  = M_H_CPU0_SA_DQ<16>
  VSS11  = GND
  DQ17_A  = M_H_CPU0_SA_DQ<17>
  VSS12  = GND
  DQS2_A_T  = M_H_CPU0_SA_DQS_DP<2>
  DQS2_A_C  = M_H_CPU0_SA_DQS_DN<2>
  VSS13  = GND
  DQ20_A  = M_H_CPU0_SA_DQ<20>
  VSS14  = GND
  DQ21_A  = M_H_CPU0_SA_DQ<21>
  VSS15  = GND
  DQ24_A  = M_H_CPU0_SA_DQ<24>
  VSS16  = GND
  DQ25_A  = M_H_CPU0_SA_DQ<25>
  VSS17  = GND
  DQS3_A_T  = M_H_CPU0_SA_DQS_DP<3>
  DQS3_A_C  = M_H_CPU0_SA_DQS_DN<3>
  VSS18  = GND
  DQ28_A  = M_H_CPU0_SA_DQ<28>
  VSS19  = GND
  DQ29_A  = M_H_CPU0_SA_DQ<29>
  VSS20  = GND
  CB0_A  = M_H_CPU0_SA_CB<0>
  VSS21  = GND
  CB1_A  = M_H_CPU0_SA_CB<1>
  VSS22  = GND
  DQS4_A_T  = M_H_CPU0_SA_DQS_DP<4>
  DQS4_A_C  = M_H_CPU0_SA_DQS_DN<4>
  VSS23  = GND
  CB4_A  = M_H_CPU0_SA_CB<4>
  VSS24  = GND
  CB5_A  = M_H_CPU0_SA_CB<5>
  VSS25  = GND
  ALERT_N  = M_H_CPU0_ALERT_N
  VSS26  = GND
  CS0_A_N  = M_H_CPU0_SA_CS_N<0>
  VSS27  = GND
  CA0_A  = M_H_CPU0_SA_CA<0>
  VSS28  = GND
  CA2_A  = M_H_CPU0_SA_CA<2>
  VSS29  = GND
  CA4_A  = M_H_CPU0_SA_CA<4>
  VSS30  = GND
  CA6_A  = M_H_CPU0_SA_CA<6>
  VSS31  = GND
  PAR_A  = M_H_CPU0_SA_PAR
  VSS32  = GND
  CA0_B  = M_H_CPU0_SB_CA<0>
  VSS33  = GND
  CA2_B  = M_H_CPU0_SB_CA<2>
  VSS34  = GND
  CA4_B  = M_H_CPU0_SB_CA<4>
  VSS35  = GND
  CA6_B  = M_H_CPU0_SB_CA<6>
  VSS36  = GND
  CS0_B_N  = M_H_CPU0_SB_CS_N<0>
  VSS37  = GND
  \lbd||rsp_a_n\  = M_H_CPU0_SA_RSP<0>
  \lbs||rsp_b_n\  = M_H_CPU0_SB_RSP<0>
  VSS38  = GND
  CB4_B  = M_H_CPU0_SB_CB<4>
  VSS39  = GND
  CB5_B  = M_H_CPU0_SB_CB<5>
  VSS40  = GND
  \dqs9_b_t||tdqs9_b_t||dbi4_b_n\  = M_H_CPU0_SB_DQS_DP<9>
  \dqs9_b_c||tdqs9_b_c\  = M_H_CPU0_SB_DQS_DN<9>
  VSS41  = GND
  CB0_B  = M_H_CPU0_SB_CB<0>
  VSS42  = GND
  CB1_B  = M_H_CPU0_SB_CB<1>
  VSS43  = GND
  DQ0_B  = M_H_CPU0_SB_DQ<0>
  VSS44  = GND
  DQ1_B  = M_H_CPU0_SB_DQ<1>
  VSS45  = GND
  DQS0_B_T  = M_H_CPU0_SB_DQS_DP<0>
  DQS0_B_C  = M_H_CPU0_SB_DQS_DN<0>
  VSS46  = GND
  DQ4_B  = M_H_CPU0_SB_DQ<4>
  VSS47  = GND
  DQ5_B  = M_H_CPU0_SB_DQ<5>
  VSS48  = GND
  DQ8_B  = M_H_CPU0_SB_DQ<8>
  VSS49  = GND
  DQ9_B  = M_H_CPU0_SB_DQ<9>
  VSS50  = GND
  DQS1_B_T  = M_H_CPU0_SB_DQS_DP<1>
  DQS1_B_C  = M_H_CPU0_SB_DQS_DN<1>
  VSS51  = GND
  DQ12_B  = M_H_CPU0_SB_DQ<12>
  VSS52  = GND
  DQ13_B  = M_H_CPU0_SB_DQ<13>
  VSS53  = GND
  DQ16_B  = M_H_CPU0_SB_DQ<16>
  VSS54  = GND
  DQ17_B  = M_H_CPU0_SB_DQ<17>
  VSS55  = GND
  DQS2_B_T  = M_H_CPU0_SB_DQS_DP<2>
  DQS2_B_C  = M_H_CPU0_SB_DQS_DN<2>
  VSS56  = GND
  DQ20_B  = M_H_CPU0_SB_DQ<20>
  VSS57  = GND
  DQ21_B  = M_H_CPU0_SB_DQ<21>
  VSS58  = GND
  DQ24_B  = M_H_CPU0_SB_DQ<24>
  VSS59  = GND
  DQ25_B  = M_H_CPU0_SB_DQ<25>
  VSS60  = GND
  DQS3_B_T  = M_H_CPU0_SB_DQS_DP<3>
  DQS3_B_C  = M_H_CPU0_SB_DQS_DN<3>
  VSS61  = GND
  DQ28_B  = M_H_CPU0_SB_DQ<28>
  VSS62  = GND
  DQ29_B  = M_H_CPU0_SB_DQ<29>
  VSS63  = GND
  RFU1  = TP_CHH_CPU0_DIMM1_FRU_1
  VIN_BULK1  = P12V_S3_AUX_CPU0_NVDIMM
  VIN_BULK2  = P12V_S3_AUX_CPU0_NVDIMM
  \pwr_good||fail_n\  = PWRGD_CHH_CPU0_DIMM1
  HSA  = PD_CHH_CPU0_DIMM1_SAA
  RFU2  = TP_CHH_CPU0_DIMM1_FRU_2
  RFU3  = TP_CHH_CPU0_DIMM1_FRU_3
  VSS64  = GND
  DQ2_A  = M_H_CPU0_SA_DQ<2>
  VSS65  = GND
  DQ3_A  = M_H_CPU0_SA_DQ<3>
  VSS66  = GND
  \dqs5_a_c||tdqs5_a_c||dqs5_a_t||tdqs5_a_t\  = M_H_CPU0_SA_DQS_DN<5>
  \dqs5_a_t||tdqs5_a_t\  = M_H_CPU0_SA_DQS_DP<5>
  VSS67  = GND
  DQ6_A  = M_H_CPU0_SA_DQ<6>
  VSS68  = GND
  DQ7_A  = M_H_CPU0_SA_DQ<7>
  VSS69  = GND
  DQ10_A  = M_H_CPU0_SA_DQ<10>
  VSS70  = GND
  DQ11_A  = M_H_CPU0_SA_DQ<11>
  VSS71  = GND
  \dqs6_a_c||tdqs6_a_c||dqs6_a_t||tdqs6_a_t\  = M_H_CPU0_SA_DQS_DN<6>
  \dqs6_a_t||tdqs6_a_t\  = M_H_CPU0_SA_DQS_DP<6>
  VSS72  = GND
  DQ14_A  = M_H_CPU0_SA_DQ<14>
  VSS73  = GND
  DQ15_A  = M_H_CPU0_SA_DQ<15>
  VSS74  = GND
  DQ18_A  = M_H_CPU0_SA_DQ<18>
  VSS75  = GND
  DQ19_A  = M_H_CPU0_SA_DQ<19>
  VSS76  = GND
  \dqs7_a_c||tdqs7_a_c\  = M_H_CPU0_SA_DQS_DN<7>
  \dqs7_a_t||tdqs7_a_t\  = M_H_CPU0_SA_DQS_DP<7>
  VSS77  = GND
  DQ22_A  = M_H_CPU0_SA_DQ<22>
  VSS78  = GND
  DQ23_A  = M_H_CPU0_SA_DQ<23>
  VSS79  = GND
  DQ26_A  = M_H_CPU0_SA_DQ<26>
  VSS80  = GND
  DQ27_A  = M_H_CPU0_SA_DQ<27>
  VSS81  = GND
  \dqs8_a_c||tdqs8_a_c\  = M_H_CPU0_SA_DQS_DN<8>
  \dqs8_a_t||tdqs8_a_t\  = M_H_CPU0_SA_DQS_DP<8>
  VSS82  = GND
  DQ30_A  = M_H_CPU0_SA_DQ<30>
  VSS83  = GND
  DQ31_A  = M_H_CPU0_SA_DQ<31>
  VSS84  = GND
  CB2_A  = M_H_CPU0_SA_CB<2>
  VSS85  = GND
  CB3_A  = M_H_CPU0_SA_CB<3>
  VSS86  = GND
  \dqs9_a_c||tdqs9_a_c\  = M_H_CPU0_SA_DQS_DN<9>
  \dqs9_a_t||tdqs9_a_t\  = M_H_CPU0_SA_DQS_DP<9>
  VSS87  = GND
  CB6_A  = M_H_CPU0_SA_CB<6>
  VSS88  = GND
  CB7_A  = M_H_CPU0_SA_CB<7>
  VSS89  = GND
  RESET_N  = RST_M_GH_CPU0_FPGA_N
  VSS90  = GND
  CS1_A_N  = M_H_CPU0_SA_CS_N<1>
  VSS91  = GND
  CA1_A  = M_H_CPU0_SA_CA<1>
  VSS92  = GND
  CA3_A  = M_H_CPU0_SA_CA<3>
  VSS93  = GND
  CA5_A  = M_H_CPU0_SA_CA<5>
  VSS94  = GND
  CK_T  = M_H_CPU0_CLK_DP<0>
  CK_C  = M_H_CPU0_CLK_DN<0>
  VSS95  = GND
  RFU4  = TP_CHH_CPU0_DIMM1_FRU_4
  CA1_B  = M_H_CPU0_SB_CA<1>
  VSS96  = GND
  CA3_B  = M_H_CPU0_SB_CA<3>
  VSS97  = GND
  CA5_B  = M_H_CPU0_SB_CA<5>
  VSS98  = GND
  PAR_B  = M_H_CPU0_SB_PAR
  VSS99  = GND
  CS1_B_N  = M_H_CPU0_SB_CS_N<1>
  VSS100  = GND
  RFU5  = TP_CHH_CPU0_DIMM1_FRU_5
  RFU6  = TP_CHH_CPU0_DIMM1_FRU_6
  VSS101  = GND
  CB6_B  = M_H_CPU0_SB_CB<6>
  VSS102  = GND
  CB7_B  = M_H_CPU0_SB_CB<7>
  VSS103  = GND
  DQS4_B_C  = M_H_CPU0_SB_DQS_DN<4>
  DQS4_B_T  = M_H_CPU0_SB_DQS_DP<4>
  VSS104  = GND
  CB2_B  = M_H_CPU0_SB_CB<2>
  VSS105  = GND
  CB3_B  = M_H_CPU0_SB_CB<3>
  VSS106  = GND
  DQ2_B  = M_H_CPU0_SB_DQ<2>
  VSS107  = GND
  DQ3_B  = M_H_CPU0_SB_DQ<3>
  VSS108  = GND
  \dqs5_b_c||tdqs5_b_c\  = M_H_CPU0_SB_DQS_DN<5>
  \dqs5_b_t||tdqs5_b_t\  = M_H_CPU0_SB_DQS_DP<5>
  VSS109  = GND
  DQ6_B  = M_H_CPU0_SB_DQ<6>
  VSS110  = GND
  DQ7_B  = M_H_CPU0_SB_DQ<7>
  VSS111  = GND
  DQ10_B  = M_H_CPU0_SB_DQ<10>
  VSS112  = GND
  DQ11_B  = M_H_CPU0_SB_DQ<11>
  VSS113  = GND
  \dqs6_b_c||tdqs6_b_c\  = M_H_CPU0_SB_DQS_DN<6>
  \dqs6_b_t||tdqs6_b_t\  = M_H_CPU0_SB_DQS_DP<6>
  VSS114  = GND
  DQ14_B  = M_H_CPU0_SB_DQ<14>
  VSS115  = GND
  DQ15_B  = M_H_CPU0_SB_DQ<15>
  VSS116  = GND
  DQ18_B  = M_H_CPU0_SB_DQ<18>
  VSS117  = GND
  DQ19_B  = M_H_CPU0_SB_DQ<19>
  VSS118  = GND
  \dqs7_b_c||tdqs7_b_c\  = M_H_CPU0_SB_DQS_DN<7>
  \dqs7_b_t||tdqs7_b_t\  = M_H_CPU0_SB_DQS_DP<7>
  VSS119  = GND
  DQ22_B  = M_H_CPU0_SB_DQ<22>
  VSS120  = GND
  DQ23_B  = M_H_CPU0_SB_DQ<23>
  VSS121  = GND
  DQ26_B  = M_H_CPU0_SB_DQ<26>
  VSS122  = GND
  DQ27_B  = M_H_CPU0_SB_DQ<27>
  VSS123  = GND
  \dqs8_b_c||tdqs8_b_c\  = M_H_CPU0_SB_DQS_DN<8>
  \dqs8_b_t||tdqs8_b_t\  = M_H_CPU0_SB_DQS_DP<8>
  VSS124  = GND
  DQ30_B  = M_H_CPU0_SB_DQ<30>
  VSS125  = GND
  DQ31_B  = M_H_CPU0_SB_DQ<31>
  VSS126  = GND
  G1  = GND
  G2  = GND
  G3  = GND

(kicad_pcb
	(version 20260206)
	(generator "pcbnew")
	(generator_version "10.0")
	(general
		(thickness 1.6)
		(legacy_teardrops no)
	)
	(paper "A4")
	(title_block
		(title "03242023_DA0F0TMBIJ0_F0T_Motherboard_J_brd_V01_OCP.brd")
		(comment 1 "Grand Teton / footprint 2194 of 6105 (J15), pads 229-274 of 291")
	)
	(layers
		(0 "F.Cu" signal "TOP")
		(4 "In1.Cu" signal "GND")
		(6 "In2.Cu" signal "IN1")
		(8 "In3.Cu" signal "GND1")
		(10 "In4.Cu" signal "IN2")
		(12 "In5.Cu" signal "GND2")
		(14 "In6.Cu" signal "IN3")
		(16 "In7.Cu" signal "GND3")
		(18 "In8.Cu" signal "VCC")
		(20 "In9.Cu" signal "VCC1")
		(22 "In10.Cu" signal "GND4")
		(24 "In11.Cu" signal "IN4")
		(26 "In12.Cu" signal "GND5")
		(28 "In13.Cu" signal "IN5")
		(30 "In14.Cu" signal "GND6")
		(32 "In15.Cu" signal "IN6")
		(34 "In16.Cu" signal "GND7")
		(2 "B.Cu" signal "BOTTOM")
		(9 "F.Adhes" user "F.Adhesive")
		(11 "B.Adhes" user "B.Adhesive")
		(13 "F.Paste" user "Package Geometry/Pastemask Top")
		(15 "B.Paste" user "Package Geometry/Pastemask Bottom")
		(5 "F.SilkS" user "Ref Des/Silkscreen Top")
		(7 "B.SilkS" user "Ref Des/Silkscreen Bottom")
		(1 "F.Mask" user "Board Geometry/Soldermask Top")
		(3 "B.Mask" user "Board Geometry/Soldermask Bottom")
		(17 "Dwgs.User" user "User.Drawings")
		(19 "Cmts.User" user "User.Comments")
		(21 "Eco1.User" user "User.Eco1")
		(23 "Eco2.User" user "User.Eco2")
		(25 "Edge.Cuts" user "Board Geometry/Outline")
		(27 "Margin" user)
		(31 "F.CrtYd" user "Package Geometry/Place Bound Top")
		(29 "B.CrtYd" user "Package Geometry/Place Bound Bottom")
		(35 "F.Fab" user "Ref Des/Assembly Top")
		(33 "B.Fab" user "Ref Des/Assembly Bottom")
	)
	(footprint ""
		(layer "F.Cu")
		(at 461.609948 -258.091686)
		(property "Reference" "J15"
			(at 3.019552 -81.652872 0)
			(unlocked yes)
			(layer "F.SilkS")
			(effects
				(font
					(size 0.7874 0.5842)
					(thickness 0.1524)
				)
				(justify left)
			)
		)
		(property "Value" ""
			(at 0 0 0)
			(layer "F.Fab")
			(effects
				(font
					(size 1.27 1.27)
				)
			)
		)
		(duplicate_pad_numbers_are_jumpers no)
		(pad "229" smd rect
			(at 2.050034 13.17498 270)
			(size 0.519938 1.4986)
			(layers "F.Cu" "F.Mask" "F.Paste")
			(net "M_H_CPU0_SB_CS_N<1>")
		)
		(pad "230" smd rect
			(at 2.050034 14.025118 270)
			(size 0.519938 1.4986)
			(layers "F.Cu" "F.Mask" "F.Paste")
			(net "GND")
		)
		(pad "231" smd rect
			(at 2.050034 14.875002 270)
			(size 0.519938 1.4986)
			(layers "F.Cu" "F.Mask" "F.Paste")
			(net "TP_CHH_CPU0_DIMM1_FRU_5")
		)
		(pad "232" smd rect
			(at 2.050034 15.724886 270)
			(size 0.519938 1.4986)
			(layers "F.Cu" "F.Mask" "F.Paste")
			(net "TP_CHH_CPU0_DIMM1_FRU_6")
		)
		(pad "233" smd rect
			(at 2.050034 16.575024 270)
			(size 0.519938 1.4986)
			(layers "F.Cu" "F.Mask" "F.Paste")
			(net "GND")
		)
		(pad "234" smd rect
			(at 2.050034 17.424908 270)
			(size 0.519938 1.4986)
			(layers "F.Cu" "F.Mask" "F.Paste")
			(net "M_H_CPU0_SB_CB<6>")
		)
		(pad "235" smd rect
			(at 2.050034 18.275046 270)
			(size 0.519938 1.4986)
			(layers "F.Cu" "F.Mask" "F.Paste")
			(net "GND")
		)
		(pad "236" smd rect
			(at 2.050034 19.12493 270)
			(size 0.519938 1.4986)
			(layers "F.Cu" "F.Mask" "F.Paste")
			(net "M_H_CPU0_SB_CB<7>")
		)
		(pad "237" smd rect
			(at 2.050034 19.975068 270)
			(size 0.519938 1.4986)
			(layers "F.Cu" "F.Mask" "F.Paste")
			(net "GND")
		)
		(pad "238" smd rect
			(at 2.050034 20.824952 270)
			(size 0.519938 1.4986)
			(layers "F.Cu" "F.Mask" "F.Paste")
			(net "M_H_CPU0_SB_DQS_DN<4>")
		)
		(pad "239" smd rect
			(at 2.050034 21.67509 270)
			(size 0.519938 1.4986)
			(layers "F.Cu" "F.Mask" "F.Paste")
			(net "M_H_CPU0_SB_DQS_DP<4>")
		)
		(pad "240" smd rect
			(at 2.050034 22.524974 270)
			(size 0.519938 1.4986)
			(layers "F.Cu" "F.Mask" "F.Paste")
			(net "GND")
		)
		(pad "241" smd rect
			(at 2.050034 23.375112 270)
			(size 0.519938 1.4986)
			(layers "F.Cu" "F.Mask" "F.Paste")
			(net "M_H_CPU0_SB_CB<2>")
		)
		(pad "242" smd rect
			(at 2.050034 24.224996 270)
			(size 0.519938 1.4986)
			(layers "F.Cu" "F.Mask" "F.Paste")
			(net "GND")
		)
		(pad "243" smd rect
			(at 2.050034 25.07488 270)
			(size 0.519938 1.4986)
			(layers "F.Cu" "F.Mask" "F.Paste")
			(net "M_H_CPU0_SB_CB<3>")
		)
		(pad "244" smd rect
			(at 2.050034 25.925018 270)
			(size 0.519938 1.4986)
			(layers "F.Cu" "F.Mask" "F.Paste")
			(net "GND")
		)
		(pad "245" smd rect
			(at 2.050034 26.774902 270)
			(size 0.519938 1.4986)
			(layers "F.Cu" "F.Mask" "F.Paste")
			(net "M_H_CPU0_SB_DQ<2>")
		)
		(pad "246" smd rect
			(at 2.050034 27.62504 270)
			(size 0.519938 1.4986)
			(layers "F.Cu" "F.Mask" "F.Paste")
			(net "GND")
		)
		(pad "247" smd rect
			(at 2.050034 28.474924 270)
			(size 0.519938 1.4986)
			(layers "F.Cu" "F.Mask" "F.Paste")
			(net "M_H_CPU0_SB_DQ<3>")
		)
		(pad "248" smd rect
			(at 2.050034 29.325062 270)
			(size 0.519938 1.4986)
			(layers "F.Cu" "F.Mask" "F.Paste")
			(net "GND")
		)
		(pad "249" smd rect
			(at 2.050034 30.174946 270)
			(size 0.519938 1.4986)
			(layers "F.Cu" "F.Mask" "F.Paste")
			(net "M_H_CPU0_SB_DQS_DN<5>")
		)
		(pad "250" smd rect
			(at 2.050034 31.025084 270)
			(size 0.519938 1.4986)
			(layers "F.Cu" "F.Mask" "F.Paste")
			(net "M_H_CPU0_SB_DQS_DP<5>")
		)
		(pad "251" smd rect
			(at 2.050034 31.874968 270)
			(size 0.519938 1.4986)
			(layers "F.Cu" "F.Mask" "F.Paste")
			(net "GND")
		)
		(pad "252" smd rect
			(at 2.050034 32.725106 270)
			(size 0.519938 1.4986)
			(layers "F.Cu" "F.Mask" "F.Paste")
			(net "M_H_CPU0_SB_DQ<6>")
		)
		(pad "253" smd rect
			(at 2.050034 33.57499 270)
			(size 0.519938 1.4986)
			(layers "F.Cu" "F.Mask" "F.Paste")
			(net "GND")
		)
		(pad "254" smd rect
			(at 2.050034 34.425128 270)
			(size 0.519938 1.4986)
			(layers "F.Cu" "F.Mask" "F.Paste")
			(net "M_H_CPU0_SB_DQ<7>")
		)
		(pad "255" smd rect
			(at 2.050034 35.275012 270)
			(size 0.519938 1.4986)
			(layers "F.Cu" "F.Mask" "F.Paste")
			(net "GND")
		)
		(pad "256" smd rect
			(at 2.050034 36.124896 270)
			(size 0.519938 1.4986)
			(layers "F.Cu" "F.Mask" "F.Paste")
			(net "M_H_CPU0_SB_DQ<10>")
		)
		(pad "257" smd rect
			(at 2.050034 36.975034 270)
			(size 0.519938 1.4986)
			(layers "F.Cu" "F.Mask" "F.Paste")
			(net "GND")
		)
		(pad "258" smd rect
			(at 2.050034 37.824918 270)
			(size 0.519938 1.4986)
			(layers "F.Cu" "F.Mask" "F.Paste")
			(net "M_H_CPU0_SB_DQ<11>")
		)
		(pad "259" smd rect
			(at 2.050034 38.675056 270)
			(size 0.519938 1.4986)
			(layers "F.Cu" "F.Mask" "F.Paste")
			(net "GND")
		)
		(pad "260" smd rect
			(at 2.050034 39.52494 270)
			(size 0.519938 1.4986)
			(layers "F.Cu" "F.Mask" "F.Paste")
			(net "M_H_CPU0_SB_DQS_DN<6>")
		)
		(pad "261" smd rect
			(at 2.050034 40.375078 270)
			(size 0.519938 1.4986)
			(layers "F.Cu" "F.Mask" "F.Paste")
			(net "M_H_CPU0_SB_DQS_DP<6>")
		)
		(pad "262" smd rect
			(at 2.050034 41.224962 270)
			(size 0.519938 1.4986)
			(layers "F.Cu" "F.Mask" "F.Paste")
			(net "GND")
		)
		(pad "263" smd rect
			(at 2.050034 42.0751 270)
			(size 0.519938 1.4986)
			(layers "F.Cu" "F.Mask" "F.Paste")
			(net "M_H_CPU0_SB_DQ<14>")
		)
		(pad "264" smd rect
			(at 2.050034 42.924984 270)
			(size 0.519938 1.4986)
			(layers "F.Cu" "F.Mask" "F.Paste")
			(net "GND")
		)
		(pad "265" smd rect
			(at 2.050034 43.775122 270)
			(size 0.519938 1.4986)
			(layers "F.Cu" "F.Mask" "F.Paste")
			(net "M_H_CPU0_SB_DQ<15>")
		)
		(pad "266" smd rect
			(at 2.050034 44.625006 270)
			(size 0.519938 1.4986)
			(layers "F.Cu" "F.Mask" "F.Paste")
			(net "GND")
		)
		(pad "267" smd rect
			(at 2.050034 45.47489 270)
			(size 0.519938 1.4986)
			(layers "F.Cu" "F.Mask" "F.Paste")
			(net "M_H_CPU0_SB_DQ<18>")
		)
		(pad "268" smd rect
			(at 2.050034 46.325028 270)
			(size 0.519938 1.4986)
			(layers "F.Cu" "F.Mask" "F.Paste")
			(net "GND")
		)
		(pad "269" smd rect
			(at 2.050034 47.174912 270)
			(size 0.519938 1.4986)
			(layers "F.Cu" "F.Mask" "F.Paste")
			(net "M_H_CPU0_SB_DQ<19>")
		)
		(pad "270" smd rect
			(at 2.050034 48.02505 270)
			(size 0.519938 1.4986)
			(layers "F.Cu" "F.Mask" "F.Paste")
			(net "GND")
		)
		(pad "271" smd rect
			(at 2.050034 48.874934 270)
			(size 0.519938 1.4986)
			(layers "F.Cu" "F.Mask" "F.Paste")
			(net "M_H_CPU0_SB_DQS_DN<7>")
		)
		(pad "272" smd rect
			(at 2.050034 49.725072 270)
			(size 0.519938 1.4986)
			(layers "F.Cu" "F.Mask" "F.Paste")
			(net "M_H_CPU0_SB_DQS_DP<7>")
		)
		(pad "273" smd rect
			(at 2.050034 50.574956 270)
			(size 0.519938 1.4986)
			(layers "F.Cu" "F.Mask" "F.Paste")
			(net "GND")
		)
		(pad "274" smd rect
			(at 2.050034 51.425094 270)
			(size 0.519938 1.4986)
			(layers "F.Cu" "F.Mask" "F.Paste")
			(net "M_H_CPU0_SB_DQ<22>")
		)
	)
)
